# S9S_MB_2U (Grand Teton) — schematic netlist excerpt (pin names and nets, part order shuffled) for the footprints in the layout excerpt that follows; sources: Cadence DE-HDL packaged netlist, KiCad conversion of 03242023_DA0F0TMBIJ0_F0T_Motherboard_J_brd_V01_OCP.brd

PR3842  Q_RES  10K 1% CHIP  pkg 0402LF  page 157 : A = P12V_OCP_OV_FB_1 ; B = GND
PC235  Q_CAP  100NF 50V 10% X7R  pkg C0402  page 270 : A = SW_PVCCIN_CPU0_BOOT7_R ; B = SW_PVCCIN_CPU0_BOOTR7
PL35  Q_INDUCTOR  120NH/69A IND  pkg SMLF  page 279 : \1\ = SW_PVCCD_HV_CPU0_SW1 ; \2\ = PVCCD_HV_CPU0

(kicad_pcb
	(version 20260206)
	(generator "pcbnew")
	(generator_version "10.0")
	(general
		(thickness 1.6)
		(legacy_teardrops no)
	)
	(paper "A4")
	(title_block
		(title "03242023_DA0F0TMBIJ0_F0T_Motherboard_J_brd_V01_OCP.brd")
		(comment 1 "Grand Teton / footprints 3313-3315 of 6105")
	)
	(layers
		(0 "F.Cu" signal "TOP")
		(4 "In1.Cu" signal "GND")
		(6 "In2.Cu" signal "IN1")
		(8 "In3.Cu" signal "GND1")
		(10 "In4.Cu" signal "IN2")
		(12 "In5.Cu" signal "GND2")
		(14 "In6.Cu" signal "IN3")
		(16 "In7.Cu" signal "GND3")
		(18 "In8.Cu" signal "VCC")
		(20 "In9.Cu" signal "VCC1")
		(22 "In10.Cu" signal "GND4")
		(24 "In11.Cu" signal "IN4")
		(26 "In12.Cu" signal "GND5")
		(28 "In13.Cu" signal "IN5")
		(30 "In14.Cu" signal "GND6")
		(32 "In15.Cu" signal "IN6")
		(34 "In16.Cu" signal "GND7")
		(2 "B.Cu" signal "BOTTOM")
		(9 "F.Adhes" user "F.Adhesive")
		(11 "B.Adhes" user "B.Adhesive")
		(13 "F.Paste" user "Package Geometry/Pastemask Top")
		(15 "B.Paste" user "Package Geometry/Pastemask Bottom")
		(5 "F.SilkS" user "Ref Des/Silkscreen Top")
		(7 "B.SilkS" user "Ref Des/Silkscreen Bottom")
		(1 "F.Mask" user "Board Geometry/Soldermask Top")
		(3 "B.Mask" user "Board Geometry/Soldermask Bottom")
		(17 "Dwgs.User" user "User.Drawings")
		(19 "Cmts.User" user "User.Comments")
		(21 "Eco1.User" user "User.Eco1")
		(23 "Eco2.User" user "User.Eco2")
		(25 "Edge.Cuts" user "Board Geometry/Outline")
		(27 "Margin" user)
		(31 "F.CrtYd" user "Package Geometry/Place Bound Top")
		(29 "B.CrtYd" user "Package Geometry/Place Bound Bottom")
		(35 "F.Fab" user "Ref Des/Assembly Top")
		(33 "B.Fab" user "Ref Des/Assembly Bottom")
	)
	(footprint ""
		(layer "F.Cu")
		(at 438.558432 -27.275536 -90)
		(property "Reference" "PR3842"
			(at 0 0 270)
			(layer "F.SilkS")
			(hide yes)
			(effects
				(font
					(size 1.27 1.27)
				)
			)
		)
		(property "Value" ""
			(at 0 0 270)
			(layer "F.Fab")
			(effects
				(font
					(size 1.27 1.27)
				)
			)
		)
		(duplicate_pad_numbers_are_jumpers no)
		(fp_line
			(start -0.7874 0.4064)
			(end -0.7874 -0.4064)
			(stroke
				(width 0.1524)
				(type default)
			)
			(layer "F.SilkS")
		)
		(fp_line
			(start 0.7874 0.4064)
			(end -0.7874 0.4064)
			(stroke
				(width 0.1524)
				(type default)
			)
			(layer "F.SilkS")
		)
		(fp_line
			(start -0.7874 -0.4064)
			(end 0.7874 -0.4064)
			(stroke
				(width 0.1524)
				(type default)
			)
			(layer "F.SilkS")
		)
		(fp_line
			(start 0.7874 -0.4064)
			(end 0.7874 0.4064)
			(stroke
				(width 0.1524)
				(type default)
			)
			(layer "F.SilkS")
		)
		(fp_line
			(start -0.67945 0.3048)
			(end -0.67945 -0.305054)
			(stroke
				(width 0.1)
				(type default)
			)
			(layer "F.Fab")
		)
		(fp_line
			(start -0.12065 0.3048)
			(end -0.67945 0.3048)
			(stroke
				(width 0.1)
				(type default)
			)
			(layer "F.Fab")
		)
		(fp_line
			(start 0.120396 0.3048)
			(end 0.120396 0.2794)
			(stroke
				(width 0.1)
				(type default)
			)
			(layer "F.Fab")
		)
		(fp_line
			(start 0.67945 0.3048)
			(end 0.120396 0.3048)
			(stroke
				(width 0.1)
				(type default)
			)
			(layer "F.Fab")
		)
		(fp_line
			(start -0.12065 0.2794)
			(end -0.12065 0.3048)
			(stroke
				(width 0.1)
				(type default)
			)
			(layer "F.Fab")
		)
		(fp_line
			(start 0.120396 0.2794)
			(end -0.12065 0.2794)
			(stroke
				(width 0.1)
				(type default)
			)
			(layer "F.Fab")
		)
		(fp_line
			(start -0.12065 -0.2794)
			(end 0.12065 -0.2794)
			(stroke
				(width 0.1)
				(type default)
			)
			(layer "F.Fab")
		)
		(fp_line
			(start 0.12065 -0.2794)
			(end 0.12065 -0.3048)
			(stroke
				(width 0.1)
				(type default)
			)
			(layer "F.Fab")
		)
		(fp_line
			(start 0.12065 -0.3048)
			(end 0.67945 -0.3048)
			(stroke
				(width 0.1)
				(type default)
			)
			(layer "F.Fab")
		)
		(fp_line
			(start 0.67945 -0.3048)
			(end 0.67945 0.3048)
			(stroke
				(width 0.1)
				(type default)
			)
			(layer "F.Fab")
		)
		(fp_line
			(start -0.67945 -0.305054)
			(end -0.12065 -0.305054)
			(stroke
				(width 0.1)
				(type default)
			)
			(layer "F.Fab")
		)
		(fp_line
			(start -0.12065 -0.305054)
			(end -0.12065 -0.2794)
			(stroke
				(width 0.1)
				(type default)
			)
			(layer "F.Fab")
		)
		(pad "1" smd circle
			(at -0.40005 0 270)
			(size 0 0)
			(layers "F.Cu" "F.Mask" "F.Paste")
			(net "P12V_OCP_OV_FB_1")
		)
		(pad "2" smd circle
			(at 0.40005 0 270)
			(size 0 0)
			(layers "F.Cu" "F.Mask" "F.Paste")
			(net "GND")
		)
	)
	(footprint ""
		(layer "F.Cu")
		(at 330.432918 -347.580458 -90)
		(property "Reference" "PC235"
			(at 0 0 270)
			(layer "F.SilkS")
			(hide yes)
			(effects
				(font
					(size 1.27 1.27)
				)
			)
		)
		(property "Value" ""
			(at 0 0 270)
			(layer "F.Fab")
			(effects
				(font
					(size 1.27 1.27)
				)
			)
		)
		(duplicate_pad_numbers_are_jumpers no)
		(fp_line
			(start -0.7874 0.4064)
			(end -0.7874 -0.4064)
			(stroke
				(width 0.1524)
				(type default)
			)
			(layer "F.SilkS")
		)
		(fp_line
			(start 0.7874 0.4064)
			(end -0.7874 0.4064)
			(stroke
				(width 0.1524)
				(type default)
			)
			(layer "F.SilkS")
		)
		(fp_line
			(start -0.7874 -0.4064)
			(end 0.7874 -0.4064)
			(stroke
				(width 0.1524)
				(type default)
			)
			(layer "F.SilkS")
		)
		(fp_line
			(start 0.7874 -0.4064)
			(end 0.7874 0.4064)
			(stroke
				(width 0.1524)
				(type default)
			)
			(layer "F.SilkS")
		)
		(fp_line
			(start -0.67945 0.3048)
			(end -0.67945 -0.305054)
			(stroke
				(width 0.1)
				(type default)
			)
			(layer "F.Fab")
		)
		(fp_line
			(start -0.12065 0.3048)
			(end -0.67945 0.3048)
			(stroke
				(width 0.1)
				(type default)
			)
			(layer "F.Fab")
		)
		(fp_line
			(start 0.120396 0.3048)
			(end 0.120396 0.2794)
			(stroke
				(width 0.1)
				(type default)
			)
			(layer "F.Fab")
		)
		(fp_line
			(start 0.67945 0.3048)
			(end 0.120396 0.3048)
			(stroke
				(width 0.1)
				(type default)
			)
			(layer "F.Fab")
		)
		(fp_line
			(start -0.12065 0.2794)
			(end -0.12065 0.3048)
			(stroke
				(width 0.1)
				(type default)
			)
			(layer "F.Fab")
		)
		(fp_line
			(start 0.120396 0.2794)
			(end -0.12065 0.2794)
			(stroke
				(width 0.1)
				(type default)
			)
			(layer "F.Fab")
		)
		(fp_line
			(start -0.12065 -0.2794)
			(end 0.12065 -0.2794)
			(stroke
				(width 0.1)
				(type default)
			)
			(layer "F.Fab")
		)
		(fp_line
			(start 0.12065 -0.2794)
			(end 0.12065 -0.3048)
			(stroke
				(width 0.1)
				(type default)
			)
			(layer "F.Fab")
		)
		(fp_line
			(start 0.12065 -0.3048)
			(end 0.67945 -0.3048)
			(stroke
				(width 0.1)
				(type default)
			)
			(layer "F.Fab")
		)
		(fp_line
			(start 0.67945 -0.3048)
			(end 0.67945 0.3048)
			(stroke
				(width 0.1)
				(type default)
			)
			(layer "F.Fab")
		)
		(fp_line
			(start -0.67945 -0.305054)
			(end -0.12065 -0.305054)
			(stroke
				(width 0.1)
				(type default)
			)
			(layer "F.Fab")
		)
		(fp_line
			(start -0.12065 -0.305054)
			(end -0.12065 -0.2794)
			(stroke
				(width 0.1)
				(type default)
			)
			(layer "F.Fab")
		)
		(pad "1" smd circle
			(at -0.40005 0 270)
			(size 0 0)
			(layers "F.Cu" "F.Mask" "F.Paste")
			(net "SW_PVCCIN_CPU0_BOOT7_R")
		)
		(pad "2" smd circle
			(at 0.40005 0 270)
			(size 0 0)
			(layers "F.Cu" "F.Mask" "F.Paste")
			(net "SW_PVCCIN_CPU0_BOOTR7")
		)
	)
	(footprint ""
		(layer "F.Cu")
		(at 408.554682 -162.185858 180)
		(property "Reference" "PL35"
			(at -0.979678 4.10464 0)
			(unlocked yes)
			(layer "F.SilkS")
			(effects
				(font
					(size 0.7874 0.5842)
					(thickness 0.1524)
				)
				(justify left)
			)
		)
		(property "Value" ""
			(at 0 0 180)
			(layer "F.Fab")
			(effects
				(font
					(size 1.27 1.27)
				)
			)
		)
		(duplicate_pad_numbers_are_jumpers no)
		(fp_line
			(start 3.24993 3.24993)
			(end -3.24993 3.24993)
			(stroke
				(width 0.1524)
				(type default)
			)
			(layer "F.SilkS")
		)
		(fp_line
			(start 3.24993 2.2352)
			(end 3.24993 3.24993)
			(stroke
				(width 0.1524)
				(type default)
			)
			(layer "F.SilkS")
		)
		(fp_line
			(start 3.24993 -3.24993)
			(end 3.24993 -2.2352)
			(stroke
				(width 0.1524)
				(type default)
			)
			(layer "F.SilkS")
		)
		(fp_line
			(start -3.24993 3.24993)
			(end -3.24993 2.2352)
			(stroke
				(width 0.1524)
				(type default)
			)
			(layer "F.SilkS")
		)
		(fp_line
			(start -3.24993 -2.2352)
			(end -3.24993 -3.24993)
			(stroke
				(width 0.1524)
				(type default)
			)
			(layer "F.SilkS")
		)
		(fp_line
			(start -3.24993 -3.24993)
			(end 3.24993 -3.24993)
			(stroke
				(width 0.1524)
				(type default)
			)
			(layer "F.SilkS")
		)
		(fp_line
			(start 3.24993 3.24993)
			(end -3.24993 3.24993)
			(stroke
				(width 0.1)
				(type default)
			)
			(layer "F.Fab")
		)
		(fp_line
			(start 3.24993 -3.24993)
			(end 3.24993 3.24993)
			(stroke
				(width 0.1)
				(type default)
			)
			(layer "F.Fab")
		)
		(fp_line
			(start -3.24993 3.24993)
			(end -3.24993 -3.24993)
			(stroke
				(width 0.1)
				(type default)
			)
			(layer "F.Fab")
		)
		(fp_line
			(start -3.24993 -3.24993)
			(end 3.24993 -3.24993)
			(stroke
				(width 0.1)
				(type default)
			)
			(layer "F.Fab")
		)
		(pad "1" smd rect
			(at -2.29997 0 180)
			(size 2.0066 4.2164)
			(layers "F.Cu" "F.Mask" "F.Paste")
			(net "SW_PVCCD_HV_CPU0_SW1")
		)
		(pad "2" smd rect
			(at 2.29997 0 180)
			(size 2.0066 4.2164)
			(layers "F.Cu" "F.Mask" "F.Paste")
			(net "PVCCD_HV_CPU0")
		)
	)
)
